#ISCELL
  logical_power design_note *
  *
#ISCELL
  mstr_misc dns *
  *
#ISCELL
  pure_quanta quanta_title_block_c *
  *
#ISCELL
  logical_power vcc15 *
  page243_i1
#ISCELL
  logical_power universal_gnd *
  page243_i11
#ISCELL
  logical_power universal_power *
  page243_i12
#CELL
  pure_quanta q_res *
  page243_i13
#ISCELL
  standard offpage *
  page243_i14
#CELL
  pure_quanta mosfet_n *
  page243_i15
#CELL
  pure_quanta q_res *
  page243_i16
#ISCELL
  logical_power universal_power *
  page243_i17
#ISCELL
  logical_power universal_gnd *
  page243_i18
#CELL
  pure_quanta q_res *
  page243_i19
#CELL
  pure_quanta q_res *
  page243_i2
#ISCELL
  standard offpage *
  page243_i20
#ISCELL
  logical_power universal_power *
  page243_i3
#CELL
  pure_quanta q_cap *
  page243_i4
#CELL
  pure_quanta q_cap *
  page243_i5
#ISCELL
  logical_power universal_power *
  page243_i6
#CELL
  pure_quanta q_res *
  page243_i7
#CELL
  pure_quanta q_res *
  page243_i8
#ISCELL
  logical_power universal_gnd *
  page243_i9
